(kicad_pcb
	(version 20241229)
	(generator "pcbnew")
	(generator_version "9.0")
	(general
		(thickness 1.711)
		(legacy_teardrops no)
	)
	(paper "A4")
	(title_block
		(title "Antmicro Baseboard for Jetson AGX Thor")
		(date "2026-02-18")
		(rev "1.1.0")
		(company "Antmicro Ltd")
		(comment 1 "www.antmicro.com")
		(comment 9 "footprints 610-610 of 1170")
	)
	(layers
		(0 "F.Cu" signal)
		(4 "In1.Cu" signal)
		(6 "In2.Cu" signal)
		(8 "In3.Cu" signal)
		(10 "In4.Cu" jumper)
		(12 "In5.Cu" signal)
		(14 "In6.Cu" signal)
		(16 "In7.Cu" signal)
		(18 "In8.Cu" signal)
		(2 "B.Cu" signal)
		(9 "F.Adhes" user "F.Adhesive")
		(11 "B.Adhes" user "B.Adhesive")
		(13 "F.Paste" user)
		(15 "B.Paste" user)
		(5 "F.SilkS" user "F.Silkscreen")
		(7 "B.SilkS" user "B.Silkscreen")
		(1 "F.Mask" user)
		(3 "B.Mask" user)
		(17 "Dwgs.User" user "User.Drawings")
		(19 "Cmts.User" user "User.Comments")
		(21 "Eco1.User" user "User.Eco1")
		(23 "Eco2.User" user "User.Eco2")
		(25 "Edge.Cuts" user)
		(27 "Margin" user)
		(31 "F.CrtYd" user "F.Courtyard")
		(29 "B.CrtYd" user "B.Courtyard")
		(35 "F.Fab" user)
		(33 "B.Fab" user)
	)
	(footprint "antmicro-footprints:VQFN-24-1EP_3.8x3.8x1.0mm_P0.5mm"
		(layer "F.Cu")
		(at 65.571 62.049 90)
		(property "Reference" "U43"
			(at -3.551 0.229 180)
			(layer "F.SilkS")
			(effects
				(font
					(size 0.7 0.7)
					(thickness 0.15)
				)
				(justify left bottom)
			)
		)
		(property "Value" "PI4MSD5V9548AZDEX"
			(at 0 3.6 90)
			(layer "F.Fab")
			(effects
				(font
					(size 0.7 0.7)
					(thickness 0.15)
				)
				(justify right top)
			)
		)
		(property "Datasheet" "https://www.mouser.com/datasheet/2/115/DIOD_S_A0003139195_1-2542233.pdf"
			(at 0 0 90)
			(layer "F.Fab")
			(hide yes)
			(effects
				(font
					(size 1.27 1.27)
					(thickness 0.15)
				)
			)
		)
		(property "Description" "Logic signal switch/multiplexer/decoder"
			(at 0 0 90)
			(layer "F.Fab")
			(hide yes)
			(effects
				(font
					(size 1.27 1.27)
					(thickness 0.15)
				)
			)
		)
		(property "Manufacturer" "Diodes Incorporated"
			(at 0 0 90)
			(unlocked yes)
			(layer "F.Fab")
			(hide yes)
			(effects
				(font
					(size 1 1)
					(thickness 0.15)
				)
			)
		)
		(property "MPN" "PI4MSD5V9548AZDEX"
			(at 0 0 90)
			(unlocked yes)
			(layer "F.Fab")
			(hide yes)
			(effects
				(font
					(size 1 1)
					(thickness 0.15)
				)
			)
		)
		(property "Author" "Antmicro"
			(at 0 0 90)
			(unlocked yes)
			(layer "F.Fab")
			(hide yes)
			(effects
				(font
					(size 1 1)
					(thickness 0.15)
				)
			)
		)
		(property "License" "Apache-2.0"
			(at 0 0 90)
			(unlocked yes)
			(layer "F.Fab")
			(hide yes)
			(effects
				(font
					(size 1 1)
					(thickness 0.15)
				)
			)
		)
		(sheetname "/CSI/")
		(sheetfile "csi.kicad_sch")
		(attr smd)
		(fp_line
			(start 1.904 -1.905)
			(end 1.523 -1.905)
			(stroke
				(width 0.15)
				(type solid)
			)
			(layer "F.SilkS")
		)
		(fp_line
			(start 1.904 -1.524)
			(end 1.904 -1.905)
			(stroke
				(width 0.15)
				(type solid)
			)
			(layer "F.SilkS")
		)
		(fp_line
			(start -1.905 -1.524)
			(end -1.524 -1.905)
			(stroke
				(width 0.15)
				(type solid)
			)
			(layer "F.SilkS")
		)
		(fp_line
			(start -1.905 1.523)
			(end -1.905 1.904)
			(stroke
				(width 0.15)
				(type solid)
			)
			(layer "F.SilkS")
		)
		(fp_line
			(start 1.904 1.904)
			(end 1.904 1.523)
			(stroke
				(width 0.15)
				(type solid)
			)
			(layer "F.SilkS")
		)
		(fp_line
			(start 1.523 1.904)
			(end 1.904 1.904)
			(stroke
				(width 0.15)
				(type solid)
			)
			(layer "F.SilkS")
		)
		(fp_line
			(start -1.905 1.904)
			(end -1.524 1.904)
			(stroke
				(width 0.15)
				(type solid)
			)
			(layer "F.SilkS")
		)
		(fp_circle
			(center -2.2 -2.2)
			(end -2.15 -2.2)
			(stroke
				(width 0.15)
				(type solid)
			)
			(fill yes)
			(layer "F.SilkS")
		)
		(fp_rect
			(start -2.5 -2.5)
			(end 2.5 2.5)
			(stroke
				(width 0.05)
				(type solid)
			)
			(fill no)
			(layer "F.CrtYd")
		)
		(fp_line
			(start -1.905 -1.524)
			(end -1.524 -1.905)
			(stroke
				(width 0.15)
				(type solid)
			)
			(layer "F.Fab")
		)
		(fp_rect
			(start -1.905 1.904)
			(end 1.904 -1.905)
			(stroke
				(width 0.15)
				(type solid)
			)
			(fill no)
			(layer "F.Fab")
		)
		(fp_text user "${REFERENCE}"
			(at -2.5 4.99 90)
			(layer "F.Fab")
			(effects
				(font
					(size 0.7 0.7)
					(thickness 0.15)
				)
				(justify left bottom)
			)
		)
		(fp_text user "Author: Antmicro"
			(at -2.5 6.35 90)
			(layer "F.Fab")
			(effects
				(font
					(size 0.7 0.7)
					(thickness 0.15)
				)
				(justify left bottom)
			)
		)
		(fp_text user "License: Apache-2.0"
			(at -2.5 7.53 90)
			(layer "F.Fab")
			(effects
				(font
					(size 0.7 0.7)
					(thickness 0.15)
				)
				(justify left bottom)
			)
		)
		(pad "1" smd roundrect
			(at -1.901 -1.25 180)
			(size 0.25 0.6)
			(layers "F.Cu" "F.Mask" "F.Paste")
			(roundrect_rratio 0.25)
			(net 987 "/CSI/SDA_CAM0")
			(pinfunction "SD0")
			(pintype "bidirectional")
		)
		(pad "2" smd roundrect
			(at -1.901 -0.75 180)
			(size 0.25 0.6)
			(layers "F.Cu" "F.Mask" "F.Paste")
			(roundrect_rratio 0.25)
			(net 985 "/CSI/SCL_CAM0")
			(pinfunction "SC0")
			(pintype "bidirectional")
		)
		(pad "3" smd roundrect
			(at -1.901 -0.25 180)
			(size 0.25 0.6)
			(layers "F.Cu" "F.Mask" "F.Paste")
			(roundrect_rratio 0.25)
			(net 986 "/CSI/SDA_CAM1")
			(pinfunction "SD1")
			(pintype "bidirectional")
		)
		(pad "4" smd roundrect
			(at -1.901 0.248 180)
			(size 0.25 0.6)
			(layers "F.Cu" "F.Mask" "F.Paste")
			(roundrect_rratio 0.25)
			(net 988 "/CSI/SCL_CAM1")
			(pinfunction "SC1")
			(pintype "bidirectional")
		)
		(pad "5" smd roundrect
			(at -1.901 0.748 180)
			(size 0.25 0.6)
			(layers "F.Cu" "F.Mask" "F.Paste")
			(roundrect_rratio 0.25)
			(net 993 "/CSI/SDA_CAM2")
			(pinfunction "SD2")
			(pintype "bidirectional")
		)
		(pad "6" smd roundrect
			(at -1.901 1.249 180)
			(size 0.25 0.6)
			(layers "F.Cu" "F.Mask" "F.Paste")
			(roundrect_rratio 0.25)
			(net 994 "/CSI/SCL_CAM2")
			(pinfunction "SC2")
			(pintype "bidirectional")
		)
		(pad "7" smd roundrect
			(at -1.252 1.898 270)
			(size 0.25 0.6)
			(layers "F.Cu" "F.Mask" "F.Paste")
			(roundrect_rratio 0.25)
			(net 991 "/CSI/SDA_CAM3")
			(pinfunction "SD3")
			(pintype "bidirectional")
		)
		(pad "8" smd roundrect
			(at -0.751 1.898 270)
			(size 0.25 0.6)
			(layers "F.Cu" "F.Mask" "F.Paste")
			(roundrect_rratio 0.25)
			(net 992 "/CSI/SCL_CAM3")
			(pinfunction "SC3")
			(pintype "bidirectional")
		)
		(pad "9" smd roundrect
			(at -0.25 1.898 270)
			(size 0.25 0.6)
			(layers "F.Cu" "F.Mask" "F.Paste")
			(roundrect_rratio 0.25)
			(net 1 "GND")
			(pinfunction "GND")
			(pintype "power_in")
		)
		(pad "10" smd roundrect
			(at 0.248 1.898 270)
			(size 0.25 0.6)
			(layers "F.Cu" "F.Mask" "F.Paste")
			(roundrect_rratio 0.25)
			(net 1045 "/CSI/MUX_I2C_4_SDA")
			(pinfunction "SD4")
			(pintype "bidirectional")
		)
		(pad "11" smd roundrect
			(at 0.748 1.898 270)
			(size 0.25 0.6)
			(layers "F.Cu" "F.Mask" "F.Paste")
			(roundrect_rratio 0.25)
			(net 1046 "/CSI/MUX_I2C_4_SCL")
			(pinfunction "SC4")
			(pintype "bidirectional")
		)
		(pad "12" smd roundrect
			(at 1.249 1.898 270)
			(size 0.25 0.6)
			(layers "F.Cu" "F.Mask" "F.Paste")
			(roundrect_rratio 0.25)
			(net 1047 "/CSI/MUX_I2C_5_SDA")
			(pinfunction "SD5")
			(pintype "bidirectional")
		)
		(pad "13" smd roundrect
			(at 1.898 1.249)
			(size 0.25 0.6)
			(layers "F.Cu" "F.Mask" "F.Paste")
			(roundrect_rratio 0.25)
			(net 1048 "/CSI/MUX_I2C_5_SCL")
			(pinfunction "SC5")
			(pintype "bidirectional")
		)
		(pad "14" smd roundrect
			(at 1.898 0.748)
			(size 0.25 0.6)
			(layers "F.Cu" "F.Mask" "F.Paste")
			(roundrect_rratio 0.25)
			(net 1049 "/CSI/MUX_I2C_6_SDA")
			(pinfunction "SD6")
			(pintype "bidirectional")
		)
		(pad "15" smd roundrect
			(at 1.898 0.248)
			(size 0.25 0.6)
			(layers "F.Cu" "F.Mask" "F.Paste")
			(roundrect_rratio 0.25)
			(net 1050 "/CSI/MUX_I2C_6_SCL")
			(pinfunction "SC6")
			(pintype "bidirectional")
		)
		(pad "16" smd roundrect
			(at 1.898 -0.25)
			(size 0.25 0.6)
			(layers "F.Cu" "F.Mask" "F.Paste")
			(roundrect_rratio 0.25)
			(net 1051 "/CSI/MUX_I2C_7_SDA")
			(pinfunction "SD7")
			(pintype "bidirectional")
		)
		(pad "17" smd roundrect
			(at 1.898 -0.75)
			(size 0.25 0.6)
			(layers "F.Cu" "F.Mask" "F.Paste")
			(roundrect_rratio 0.25)
			(net 1052 "/CSI/MUX_I2C_7_SCL")
			(pinfunction "SC7")
			(pintype "bidirectional")
		)
		(pad "18" smd roundrect
			(at 1.898 -1.252)
			(size 0.25 0.6)
			(layers "F.Cu" "F.Mask" "F.Paste")
			(roundrect_rratio 0.25)
			(net 1 "GND")
			(pinfunction "A2")
			(pintype "input")
		)
		(pad "19" smd roundrect
			(at 1.249 -1.901 90)
			(size 0.25 0.6)
			(layers "F.Cu" "F.Mask" "F.Paste")
			(roundrect_rratio 0.25)
			(net 984 "/CSI/I2C_MUX_SCL")
			(pinfunction "SCL")
			(pintype "bidirectional")
		)
		(pad "20" smd roundrect
			(at 0.748 -1.901 90)
			(size 0.25 0.6)
			(layers "F.Cu" "F.Mask" "F.Paste")
			(roundrect_rratio 0.25)
			(net 982 "/CSI/I2C_MUX_SDA")
			(pinfunction "SDA")
			(pintype "bidirectional")
		)
		(pad "21" smd roundrect
			(at 0.248 -1.901 90)
			(size 0.25 0.6)
			(layers "F.Cu" "F.Mask" "F.Paste")
			(roundrect_rratio 0.25)
			(net 11 "+1V8")
			(pinfunction "VCC")
			(pintype "power_in")
		)
		(pad "22" smd roundrect
			(at -0.25 -1.901 90)
			(size 0.25 0.6)
			(layers "F.Cu" "F.Mask" "F.Paste")
			(roundrect_rratio 0.25)
			(net 980 "/CSI/I2C_MUX_A0")
			(pinfunction "A0")
			(pintype "input")
		)
		(pad "23" smd roundrect
			(at -0.75 -1.901 90)
			(size 0.25 0.6)
			(layers "F.Cu" "F.Mask" "F.Paste")
			(roundrect_rratio 0.25)
			(net 1 "GND")
			(pinfunction "A1")
			(pintype "input")
		)
		(pad "24" smd roundrect
			(at -1.252 -1.901 90)
			(size 0.25 0.6)
			(layers "F.Cu" "F.Mask" "F.Paste")
			(roundrect_rratio 0.25)
			(net 989 "/CSI/I2C_MUX_RESET")
			(pinfunction "~{RESET}")
			(pintype "input")
		)
		(pad "25" smd roundrect
			(at 0 -0.001 90)
			(size 2.1 2.1)
			(layers "F.Cu" "F.Mask" "F.Paste")
			(roundrect_rratio 0.05)
			(net 1120 "unconnected-(U43-EP-Pad25)")
			(pinfunction "EP")
			(pintype "power_in+no_connect")
		)
	)
)
